(kicad_pcb
	(version 20260206)
	(generator "pcbnew")
	(generator_version "10.0")
	(general
		(thickness 1.6)
		(legacy_teardrops no)
	)
	(paper "A4")
	(title_block
		(title "Bryce Canyon_F.DPB_16315-1-OCP.brd")
		(comment 1 "Bryce Canyon / footprints 706-712 of 2223")
	)
	(layers
		(0 "F.Cu" signal "TOP")
		(4 "In1.Cu" signal "L2GND")
		(6 "In2.Cu" signal "L3")
		(8 "In3.Cu" signal "L4GND")
		(10 "In4.Cu" signal "L5")
		(12 "In5.Cu" signal "L6VCC")
		(14 "In6.Cu" signal "L7VCC")
		(16 "In7.Cu" signal "L8")
		(18 "In8.Cu" signal "L9GND")
		(20 "In9.Cu" signal "L10")
		(22 "In10.Cu" signal "L11GND")
		(2 "B.Cu" signal "BOTTOM")
		(9 "F.Adhes" user "F.Adhesive")
		(11 "B.Adhes" user "B.Adhesive")
		(13 "F.Paste" user "Package Geometry/Pastemask Top")
		(15 "B.Paste" user "Package Geometry/Pastemask Bottom")
		(5 "F.SilkS" user "Ref Des/Silkscreen Top")
		(7 "B.SilkS" user "Ref Des/Silkscreen Bottom")
		(1 "F.Mask" user "Board Geometry/Soldermask Top")
		(3 "B.Mask" user "Board Geometry/Soldermask Bottom")
		(17 "Dwgs.User" user "User.Drawings")
		(19 "Cmts.User" user "User.Comments")
		(21 "Eco1.User" user "User.Eco1")
		(23 "Eco2.User" user "User.Eco2")
		(25 "Edge.Cuts" user "Board Geometry/Outline")
		(27 "Margin" user)
		(31 "F.CrtYd" user "Package Geometry/Place Bound Top")
		(29 "B.CrtYd" user "Package Geometry/Place Bound Bottom")
		(35 "F.Fab" user "Ref Des/Assembly Top")
		(33 "B.Fab" user "Ref Des/Assembly Bottom")
	)
	(footprint ""
		(layer "F.Cu")
		(at 275.515578 -396.682722 90)
		(property "Reference" "C593"
			(at 0 0 90)
			(layer "F.SilkS")
			(hide yes)
			(effects
				(font
					(size 1.27 1.27)
				)
			)
		)
		(property "Value" "SCD1U25V2KX-2-GP"
			(at 1.1811 -2.7051 90)
			(unlocked yes)
			(layer "F.Fab")
			(hide yes)
			(effects
				(font
					(size 1.016 1.016)
					(thickness 0.1524)
				)
			)
		)
		(property "Device Type" "C402H22"
			(at 1.1811 -4.2291 90)
			(unlocked yes)
			(layer "F.Fab")
			(hide yes)
			(effects
				(font
					(size 1.016 1.016)
					(thickness 0.1524)
				)
			)
		)
		(duplicate_pad_numbers_are_jumpers no)
		(fp_rect
			(start -0.4318 0.9525)
			(end 0.4318 -0.9525)
			(stroke
				(width 0)
				(type default)
			)
			(fill no)
			(layer "F.CrtYd")
		)
		(fp_rect
			(start -0.4318 0.9525)
			(end 0.4318 -0.9525)
			(stroke
				(width 0)
				(type default)
			)
			(fill no)
			(layer "F.Fab")
		)
		(pad "1" smd custom
			(at 0 -0.4445 90)
			(size 0.1524 0.1524)
			(layers "F.Cu" "F.Mask" "F.Paste")
			(net "P12V_IN")
			(options
				(clearance outline)
				(anchor circle)
			)
			(primitives
				(gr_poly
					(pts
						(arc
							(start 0.3048 -0.2032)
							(mid 0.275042 -0.275042)
							(end 0.2032 -0.3048)
						)
						(arc
							(start -0.2032 -0.3048)
							(mid -0.275042 -0.275042)
							(end -0.3048 -0.2032)
						)
						(arc
							(start -0.3048 0.2032)
							(mid -0.275042 0.275042)
							(end -0.2032 0.3048)
						)
						(arc
							(start 0.2032 0.3048)
							(mid 0.275042 0.275042)
							(end 0.3048 0.2032)
						)
					)
					(width 0)
					(fill yes)
				)
			)
		)
		(pad "2" smd custom
			(at 0 0.4445 90)
			(size 0.1524 0.1524)
			(layers "F.Cu" "F.Mask" "F.Paste")
			(net "GND")
			(options
				(clearance outline)
				(anchor circle)
			)
			(primitives
				(gr_poly
					(pts
						(arc
							(start 0.3048 -0.2032)
							(mid 0.275042 -0.275042)
							(end 0.2032 -0.3048)
						)
						(arc
							(start -0.2032 -0.3048)
							(mid -0.275042 -0.275042)
							(end -0.3048 -0.2032)
						)
						(arc
							(start -0.3048 0.2032)
							(mid -0.275042 0.275042)
							(end -0.2032 0.3048)
						)
						(arc
							(start 0.2032 0.3048)
							(mid 0.275042 0.275042)
							(end 0.3048 0.2032)
						)
					)
					(width 0)
					(fill yes)
				)
			)
		)
	)
	(footprint ""
		(layer "F.Cu")
		(at 346.045028 -242.25377)
		(property "Reference" "R243"
			(at 0 0 0)
			(layer "F.SilkS")
			(hide yes)
			(effects
				(font
					(size 1.27 1.27)
				)
			)
		)
		(property "Value" "130R3F-GP"
			(at -0.0254 -2.5146 0)
			(unlocked yes)
			(layer "F.Fab")
			(hide yes)
			(effects
				(font
					(size 1.016 1.016)
					(thickness 0.1524)
				)
			)
		)
		(property "Device Type" "R603H22"
			(at -0.0254 -4.0386 0)
			(unlocked yes)
			(layer "F.Fab")
			(hide yes)
			(effects
				(font
					(size 1.016 1.016)
					(thickness 0.1524)
				)
			)
		)
		(duplicate_pad_numbers_are_jumpers no)
		(fp_line
			(start -0.4826 0)
			(end -0.2032 0)
			(stroke
				(width 0.2032)
				(type default)
			)
			(layer "F.SilkS")
		)
		(fp_line
			(start 0.2032 0)
			(end 0.4826 0)
			(stroke
				(width 0.2032)
				(type default)
			)
			(layer "F.SilkS")
		)
		(fp_rect
			(start -0.5842 1.3335)
			(end 0.5842 -1.3335)
			(stroke
				(width 0)
				(type default)
			)
			(fill no)
			(layer "F.CrtYd")
		)
		(fp_rect
			(start -0.5842 1.3335)
			(end 0.5842 -1.3335)
			(stroke
				(width 0)
				(type default)
			)
			(fill no)
			(layer "F.Fab")
		)
		(pad "1" smd custom
			(at 0 -0.762)
			(size 0.2159 0.2159)
			(layers "F.Cu" "F.Mask" "F.Paste")
			(net "P5V_A_3")
			(options
				(clearance outline)
				(anchor circle)
			)
			(primitives
				(gr_poly
					(pts
						(arc
							(start -0.3302 -0.4318)
							(mid -0.402042 -0.402042)
							(end -0.4318 -0.3302)
						)
						(arc
							(start -0.4318 0.3302)
							(mid -0.402042 0.402042)
							(end -0.3302 0.4318)
						)
						(arc
							(start 0.3302 0.4318)
							(mid 0.402042 0.402042)
							(end 0.4318 0.3302)
						)
						(arc
							(start 0.4318 -0.3302)
							(mid 0.402042 -0.402042)
							(end 0.3302 -0.4318)
						)
					)
					(width 0)
					(fill yes)
				)
			)
		)
		(pad "2" smd custom
			(at 0 0.762)
			(size 0.2159 0.2159)
			(layers "F.Cu" "F.Mask" "F.Paste")
			(net "FLT_HDD7")
			(options
				(clearance outline)
				(anchor circle)
			)
			(primitives
				(gr_poly
					(pts
						(arc
							(start -0.3302 -0.4318)
							(mid -0.402042 -0.402042)
							(end -0.4318 -0.3302)
						)
						(arc
							(start -0.4318 0.3302)
							(mid -0.402042 0.402042)
							(end -0.3302 0.4318)
						)
						(arc
							(start 0.3302 0.4318)
							(mid 0.402042 0.402042)
							(end 0.4318 0.3302)
						)
						(arc
							(start 0.4318 -0.3302)
							(mid 0.402042 -0.402042)
							(end 0.3302 -0.4318)
						)
					)
					(width 0)
					(fill yes)
				)
			)
		)
	)
	(footprint ""
		(layer "F.Cu")
		(at 147.390866 -131.656074 180)
		(property "Reference" "R1050"
			(at 0 0 180)
			(layer "F.SilkS")
			(hide yes)
			(effects
				(font
					(size 1.27 1.27)
				)
			)
		)
		(property "Value" "100KR2F-L1-GP"
			(at 0.064008 -3.993896 180)
			(unlocked yes)
			(layer "F.Fab")
			(hide yes)
			(effects
				(font
					(size 1.016 1.016)
					(thickness 0.1524)
				)
			)
		)
		(property "Device Type" "R402H16"
			(at 0.064008 -5.517896 180)
			(unlocked yes)
			(layer "F.Fab")
			(hide yes)
			(effects
				(font
					(size 1.016 1.016)
					(thickness 0.1524)
				)
			)
		)
		(duplicate_pad_numbers_are_jumpers no)
		(fp_line
			(start 0.508 -0.9398)
			(end -0.508 -0.9398)
			(stroke
				(width 0.1524)
				(type default)
			)
			(layer "F.SilkS")
		)
		(fp_line
			(start -0.508 -0.9398)
			(end -0.508 0.9398)
			(stroke
				(width 0.1524)
				(type default)
			)
			(layer "F.SilkS")
		)
		(fp_rect
			(start -0.508 0.9398)
			(end 0.508 -0.9398)
			(stroke
				(width 0)
				(type default)
			)
			(fill no)
			(layer "F.CrtYd")
		)
		(fp_rect
			(start -0.508 0.9398)
			(end 0.508 -0.9398)
			(stroke
				(width 0)
				(type default)
			)
			(fill no)
			(layer "F.Fab")
		)
		(pad "1" smd custom
			(at 0 -0.4445 180)
			(size 0.1397 0.1397)
			(layers "F.Cu" "F.Mask" "F.Paste")
			(net "P12V_A_COMP")
			(options
				(clearance outline)
				(anchor circle)
			)
			(primitives
				(gr_poly
					(pts
						(arc
							(start -0.1778 -0.2794)
							(mid -0.249642 -0.249642)
							(end -0.2794 -0.1778)
						)
						(arc
							(start -0.2794 0.1778)
							(mid -0.249642 0.249642)
							(end -0.1778 0.2794)
						)
						(arc
							(start 0.1778 0.2794)
							(mid 0.249642 0.249642)
							(end 0.2794 0.1778)
						)
						(arc
							(start 0.2794 -0.1778)
							(mid 0.249642 -0.249642)
							(end 0.1778 -0.2794)
						)
					)
					(width 0)
					(fill yes)
				)
			)
		)
		(pad "2" smd custom
			(at 0 0.4445 180)
			(size 0.1397 0.1397)
			(layers "F.Cu" "F.Mask" "F.Paste")
			(net "MB0_P12V_PWGIN_R")
			(options
				(clearance outline)
				(anchor circle)
			)
			(primitives
				(gr_poly
					(pts
						(arc
							(start -0.1778 -0.2794)
							(mid -0.249642 -0.249642)
							(end -0.2794 -0.1778)
						)
						(arc
							(start -0.2794 0.1778)
							(mid -0.249642 0.249642)
							(end -0.1778 0.2794)
						)
						(arc
							(start 0.1778 0.2794)
							(mid 0.249642 0.249642)
							(end 0.2794 0.1778)
						)
						(arc
							(start 0.2794 -0.1778)
							(mid 0.249642 -0.249642)
							(end 0.1778 -0.2794)
						)
					)
					(width 0)
					(fill yes)
				)
			)
		)
	)
	(footprint ""
		(layer "F.Cu")
		(at 32.274002 -254.43815 -90)
		(property "Reference" "R1208"
			(at 0 0 270)
			(layer "F.SilkS")
			(hide yes)
			(effects
				(font
					(size 1.27 1.27)
				)
			)
		)
		(property "Value" "10KR2F-2-GP"
			(at 0.064008 -3.993896 270)
			(unlocked yes)
			(layer "F.Fab")
			(hide yes)
			(effects
				(font
					(size 1.016 1.016)
					(thickness 0.1524)
				)
			)
		)
		(property "Device Type" "R402H16"
			(at 0.064008 -5.517896 270)
			(unlocked yes)
			(layer "F.Fab")
			(hide yes)
			(effects
				(font
					(size 1.016 1.016)
					(thickness 0.1524)
				)
			)
		)
		(duplicate_pad_numbers_are_jumpers no)
		(fp_line
			(start -0.508 -0.9398)
			(end -0.508 0.9398)
			(stroke
				(width 0.1524)
				(type default)
			)
			(layer "F.SilkS")
		)
		(fp_line
			(start 0.508 -0.9398)
			(end -0.508 -0.9398)
			(stroke
				(width 0.1524)
				(type default)
			)
			(layer "F.SilkS")
		)
		(fp_rect
			(start -0.508 0.9398)
			(end 0.508 -0.9398)
			(stroke
				(width 0)
				(type default)
			)
			(fill no)
			(layer "F.CrtYd")
		)
		(fp_rect
			(start -0.508 0.9398)
			(end 0.508 -0.9398)
			(stroke
				(width 0)
				(type default)
			)
			(fill no)
			(layer "F.Fab")
		)
		(pad "1" smd custom
			(at 0 -0.4445 270)
			(size 0.1397 0.1397)
			(layers "F.Cu" "F.Mask" "F.Paste")
			(net "P5V_A_EN_R")
			(options
				(clearance outline)
				(anchor circle)
			)
			(primitives
				(gr_poly
					(pts
						(arc
							(start -0.1778 -0.2794)
							(mid -0.249642 -0.249642)
							(end -0.2794 -0.1778)
						)
						(arc
							(start -0.2794 0.1778)
							(mid -0.249642 0.249642)
							(end -0.1778 0.2794)
						)
						(arc
							(start 0.1778 0.2794)
							(mid 0.249642 0.249642)
							(end 0.2794 0.1778)
						)
						(arc
							(start 0.2794 -0.1778)
							(mid 0.249642 -0.249642)
							(end 0.1778 -0.2794)
						)
					)
					(width 0)
					(fill yes)
				)
			)
		)
		(pad "2" smd custom
			(at 0 0.4445 270)
			(size 0.1397 0.1397)
			(layers "F.Cu" "F.Mask" "F.Paste")
			(net "GND")
			(options
				(clearance outline)
				(anchor circle)
			)
			(primitives
				(gr_poly
					(pts
						(arc
							(start -0.1778 -0.2794)
							(mid -0.249642 -0.249642)
							(end -0.2794 -0.1778)
						)
						(arc
							(start -0.2794 0.1778)
							(mid -0.249642 0.249642)
							(end -0.1778 0.2794)
						)
						(arc
							(start 0.1778 0.2794)
							(mid 0.249642 0.249642)
							(end 0.2794 0.1778)
						)
						(arc
							(start 0.2794 -0.1778)
							(mid 0.249642 -0.249642)
							(end 0.1778 -0.2794)
						)
					)
					(width 0)
					(fill yes)
				)
			)
		)
	)
	(footprint ""
		(layer "F.Cu")
		(at 363.020102 -61.127894 -90)
		(property "Reference" "R842"
			(at 0 0 270)
			(layer "F.SilkS")
			(hide yes)
			(effects
				(font
					(size 1.27 1.27)
				)
			)
		)
		(property "Value" "2R6F-GP"
			(at -0.0508 -4.8514 270)
			(unlocked yes)
			(layer "F.Fab")
			(hide yes)
			(effects
				(font
					(size 1.016 1.016)
					(thickness 0.1524)
				)
			)
		)
		(property "Device Type" "R1206H26"
			(at 0 -6.3754 270)
			(unlocked yes)
			(layer "F.Fab")
			(hide yes)
			(effects
				(font
					(size 1.016 1.016)
					(thickness 0.1524)
				)
			)
		)
		(duplicate_pad_numbers_are_jumpers no)
		(fp_line
			(start -1.016 2.2352)
			(end -1.016 -2.2352)
			(stroke
				(width 0.1524)
				(type default)
			)
			(layer "F.SilkS")
		)
		(fp_line
			(start 1.016 2.2352)
			(end -1.016 2.2352)
			(stroke
				(width 0.1524)
				(type default)
			)
			(layer "F.SilkS")
		)
		(fp_line
			(start -1.016 -2.2352)
			(end 1.016 -2.2352)
			(stroke
				(width 0.1524)
				(type default)
			)
			(layer "F.SilkS")
		)
		(fp_line
			(start 1.016 -2.2352)
			(end 1.016 2.2352)
			(stroke
				(width 0.1524)
				(type default)
			)
			(layer "F.SilkS")
		)
		(fp_rect
			(start -1.0922 2.3114)
			(end 1.0922 -2.3114)
			(stroke
				(width 0)
				(type default)
			)
			(fill no)
			(layer "F.CrtYd")
		)
		(fp_poly
			(pts
				(xy -1.0922 -2.3114) (xy 1.0922 -2.3114) (xy 1.0922 2.3114) (xy -1.0922 2.3114)
			)
			(stroke
				(width 0)
				(type default)
			)
			(fill no)
			(layer "F.Fab")
		)
		(pad "1" smd rect
			(at 0 -1.397 270)
			(size 1.651 1.27)
			(layers "F.Cu" "F.Mask" "F.Paste")
			(net "P5V_HDD31")
		)
		(pad "2" smd rect
			(at 0 1.397 270)
			(size 1.651 1.27)
			(layers "F.Cu" "F.Mask" "F.Paste")
			(net "5V_PRE_31")
		)
	)
	(footprint ""
		(layer "F.Cu")
		(at 232.859326 -261.731506 180)
		(property "Reference" "R33"
			(at 0 0 180)
			(layer "F.SilkS")
			(hide yes)
			(effects
				(font
					(size 1.27 1.27)
				)
			)
		)
		(property "Value" "4K7R2F-GP"
			(at 0.064008 -3.993896 180)
			(unlocked yes)
			(layer "F.Fab")
			(hide yes)
			(effects
				(font
					(size 1.016 1.016)
					(thickness 0.1524)
				)
			)
		)
		(property "Device Type" "R402H16"
			(at 0.064008 -5.517896 180)
			(unlocked yes)
			(layer "F.Fab")
			(hide yes)
			(effects
				(font
					(size 1.016 1.016)
					(thickness 0.1524)
				)
			)
		)
		(duplicate_pad_numbers_are_jumpers no)
		(fp_line
			(start 0.508 -0.9398)
			(end -0.508 -0.9398)
			(stroke
				(width 0.1524)
				(type default)
			)
			(layer "F.SilkS")
		)
		(fp_line
			(start -0.508 -0.9398)
			(end -0.508 0.9398)
			(stroke
				(width 0.1524)
				(type default)
			)
			(layer "F.SilkS")
		)
		(fp_rect
			(start -0.508 0.9398)
			(end 0.508 -0.9398)
			(stroke
				(width 0)
				(type default)
			)
			(fill no)
			(layer "F.CrtYd")
		)
		(fp_rect
			(start -0.508 0.9398)
			(end 0.508 -0.9398)
			(stroke
				(width 0)
				(type default)
			)
			(fill no)
			(layer "F.Fab")
		)
		(pad "1" smd custom
			(at 0 -0.4445 180)
			(size 0.1397 0.1397)
			(layers "F.Cu" "F.Mask" "F.Paste")
			(net "IO_EXP4_A2")
			(options
				(clearance outline)
				(anchor circle)
			)
			(primitives
				(gr_poly
					(pts
						(arc
							(start -0.1778 -0.2794)
							(mid -0.249642 -0.249642)
							(end -0.2794 -0.1778)
						)
						(arc
							(start -0.2794 0.1778)
							(mid -0.249642 0.249642)
							(end -0.1778 0.2794)
						)
						(arc
							(start 0.1778 0.2794)
							(mid 0.249642 0.249642)
							(end 0.2794 0.1778)
						)
						(arc
							(start 0.2794 -0.1778)
							(mid 0.249642 -0.249642)
							(end 0.1778 -0.2794)
						)
					)
					(width 0)
					(fill yes)
				)
			)
		)
		(pad "2" smd custom
			(at 0 0.4445 180)
			(size 0.1397 0.1397)
			(layers "F.Cu" "F.Mask" "F.Paste")
			(net "GND")
			(options
				(clearance outline)
				(anchor circle)
			)
			(primitives
				(gr_poly
					(pts
						(arc
							(start -0.1778 -0.2794)
							(mid -0.249642 -0.249642)
							(end -0.2794 -0.1778)
						)
						(arc
							(start -0.2794 0.1778)
							(mid -0.249642 0.249642)
							(end -0.1778 0.2794)
						)
						(arc
							(start 0.1778 0.2794)
							(mid 0.249642 0.249642)
							(end 0.2794 0.1778)
						)
						(arc
							(start 0.2794 -0.1778)
							(mid 0.249642 -0.249642)
							(end 0.1778 -0.2794)
						)
					)
					(width 0)
					(fill yes)
				)
			)
		)
	)
	(footprint ""
		(layer "F.Cu")
		(at 205.232 -308.3052)
		(property "Reference" "TC13"
			(at 0 0 0)
			(layer "F.SilkS")
			(hide yes)
			(effects
				(font
					(size 1.27 1.27)
				)
			)
		)
		(property "Value" "SE270U16VM-8-GP"
			(at -4.5974 -2.54 0)
			(unlocked yes)
			(layer "F.Fab")
			(hide yes)
			(effects
				(font
					(size 1.016 1.016)
					(thickness 0.1524)
				)
			)
		)
		(property "Device Type" "SE361416H394"
			(at -4.5974 -4.064 0)
			(unlocked yes)
			(layer "F.Fab")
			(hide yes)
			(effects
				(font
					(size 1.016 1.016)
					(thickness 0.1524)
				)
			)
		)
		(duplicate_pad_numbers_are_jumpers no)
		(fp_line
			(start -3.556 -3.4163)
			(end -2.3622 -4.6101)
			(stroke
				(width 0.1524)
				(type default)
			)
			(layer "F.SilkS")
		)
		(fp_line
			(start -3.556 4.6101)
			(end -3.556 -3.4163)
			(stroke
				(width 0.1524)
				(type default)
			)
			(layer "F.SilkS")
		)
		(fp_line
			(start -2.3622 -4.6101)
			(end 2.3622 -4.6101)
			(stroke
				(width 0.1524)
				(type default)
			)
			(layer "F.SilkS")
		)
		(fp_line
			(start 2.3622 -4.6101)
			(end 3.556 -3.4163)
			(stroke
				(width 0.1524)
				(type default)
			)
			(layer "F.SilkS")
		)
		(fp_line
			(start 3.556 -3.4163)
			(end 3.556 4.6101)
			(stroke
				(width 0.1524)
				(type default)
			)
			(layer "F.SilkS")
		)
		(fp_line
			(start 3.556 4.6101)
			(end -3.556 4.6101)
			(stroke
				(width 0.1524)
				(type default)
			)
			(layer "F.SilkS")
		)
		(fp_rect
			(start -3.302 3.6449)
			(end 3.302 -3.6449)
			(stroke
				(width 0)
				(type default)
			)
			(fill no)
			(layer "F.CrtYd")
		)
		(fp_poly
			(pts
				(xy 3.81 4.6863) (xy 3.81 -3.4925) (xy 3.302 -3.4925) (xy 3.302 3.6449) (xy -3.302 3.6449) (xy -3.302 -3.6449)
				(xy 3.302 -3.6449) (xy 3.302 -3.5052) (xy 3.81 -3.5052) (xy 3.81 -4.6863) (xy -3.81 -4.6863) (xy -3.81 4.6863)
			)
			(stroke
				(width 0)
				(type default)
			)
			(fill no)
			(layer "F.CrtYd")
		)
		(fp_rect
			(start -3.81 4.6863)
			(end 3.81 -4.6863)
			(stroke
				(width 0)
				(type default)
			)
			(fill no)
			(layer "F.Fab")
		)
		(pad "1" smd rect
			(at 0 -2.574036)
			(size 1.4224 3.556)
			(layers "F.Cu" "F.Mask" "F.Paste")
			(net "P12V_A")
		)
		(pad "2" smd rect
			(at 0 2.574036)
			(size 1.4224 3.556)
			(layers "F.Cu" "F.Mask" "F.Paste")
			(net "GND")
		)
	)
)
